# T6G (Grand Teton) — schematic netlist excerpt (pin names and nets, part order shuffled) for the footprints in the layout excerpt that follows; sources: Cadence DE-HDL packaged netlist, KiCad conversion of 04192023_DAF0TMB3IC0_F0TG_MB_C_brd_V02_OCP.brd

J20  SCONN288_DDR506112002KQ  IO  pkg DDR288S_1-1VXC  page 96
  VIN_BULK0  = P12V_MEM_CPU0
  RFU0  = NC
  VIN_MGMT  = P3V3_AUX
  HSCL  = I3C_SPD_DDRK_CPU0_SCL
  HSDA  = I3C_SPD_DDRK_CPU0_SDA
  VSS0  = GND
  DQ0_A  = M_K_CPU0_SA_DQ<0>
  VSS1  = GND
  DQ1_A  = M_K_CPU0_SA_DQ<1>
  VSS2  = GND
  DQS0_A_T  = M_K_CPU0_SA_DQS_DP<0>
  DQS0_A_C  = M_K_CPU0_SA_DQS_DN<0>
  VSS3  = GND
  DQ4_A  = M_K_CPU0_SA_DQ<4>
  VSS4  = GND
  DQ5_A  = M_K_CPU0_SA_DQ<5>
  VSS5  = GND
  DQ8_A  = M_K_CPU0_SA_DQ<8>
  VSS6  = GND
  DQ9_A  = M_K_CPU0_SA_DQ<9>
  VSS7  = GND
  DQS1_A_T  = M_K_CPU0_SA_DQS_DP<1>
  DQS1_A_C  = M_K_CPU0_SA_DQS_DN<1>
  VSS8  = GND
  DQ12_A  = M_K_CPU0_SA_DQ<12>
  VSS9  = GND
  DQ13_A  = M_K_CPU0_SA_DQ<13>
  VSS10  = GND
  DQ16_A  = M_K_CPU0_SA_DQ<16>
  VSS11  = GND
  DQ17_A  = M_K_CPU0_SA_DQ<17>
  VSS12  = GND
  DQS2_A_T  = M_K_CPU0_SA_DQS_DP<2>
  DQS2_A_C  = M_K_CPU0_SA_DQS_DN<2>
  VSS13  = GND
  DQ20_A  = M_K_CPU0_SA_DQ<20>
  VSS14  = GND
  DQ21_A  = M_K_CPU0_SA_DQ<21>
  VSS15  = GND
  DQ24_A  = M_K_CPU0_SA_DQ<24>
  VSS16  = GND
  DQ25_A  = M_K_CPU0_SA_DQ<25>
  VSS17  = GND
  DQS3_A_T  = M_K_CPU0_SA_DQS_DP<3>
  DQS3_A_C  = M_K_CPU0_SA_DQS_DN<3>
  VSS18  = GND
  DQ28_A  = M_K_CPU0_SA_DQ<28>
  VSS19  = GND
  DQ29_A  = M_K_CPU0_SA_DQ<29>
  VSS20  = GND
  CB0_A  = M_K_CPU0_SA_CB<0>
  VSS21  = GND
  CB1_A  = M_K_CPU0_SA_CB<1>
  VSS22  = GND
  DQS4_A_T  = M_K_CPU0_SA_DQS_DP<4>
  DQS4_A_C  = M_K_CPU0_SA_DQS_DN<4>
  VSS23  = GND
  CB4_A  = M_K_CPU0_SA_CB<4>
  VSS24  = GND
  CB5_A  = M_K_CPU0_SA_CB<5>
  VSS25  = GND
  ALERT_N  = M_K_CPU0_ALERT_N
  VSS26  = GND
  CS0_A_N  = M_K_CPU0_SA_CS_N<0>
  VSS27  = GND
  CA0_A  = M_K_CPU0_SA_CA<0>
  VSS28  = GND
  CA2_A  = M_K_CPU0_SA_CA<2>
  VSS29  = GND
  CA4_A  = M_K_CPU0_SA_CA<4>
  VSS30  = GND
  CA6_A  = M_K_CPU0_SA_CA<6>
  VSS31  = GND
  PAR_A  = M_K_CPU0_SA_PAR
  VSS32  = GND
  CA0_B  = M_K_CPU0_SB_CA<0>
  VSS33  = GND
  CA2_B  = M_K_CPU0_SB_CA<2>
  VSS34  = GND
  CA4_B  = M_K_CPU0_SB_CA<4>
  VSS35  = GND
  CA6_B  = M_K_CPU0_SB_CA<6>
  VSS36  = GND
  CS0_B_N  = M_K_CPU0_SB_CS_N<0>
  VSS37  = GND
  \lbd||rsp_a_n\  = M_K_CPU0_SA_RSP<0>
  \lbs||rsp_b_n\  = M_K_CPU0_SB_RSP<0>
  VSS38  = GND
  CB4_B  = M_K_CPU0_SB_CB<4>
  VSS39  = GND
  CB5_B  = M_K_CPU0_SB_CB<5>
  VSS40  = GND
  \dqs9_b_t||tdqs9_b_t||dbi4_b_n\  = M_K_CPU0_SB_DQS_DP<9>
  \dqs9_b_c||tdqs9_b_c\  = M_K_CPU0_SB_DQS_DN<9>
  VSS41  = GND
  CB0_B  = M_K_CPU0_SB_CB<0>
  VSS42  = GND
  CB1_B  = M_K_CPU0_SB_CB<1>
  VSS43  = GND
  DQ0_B  = M_K_CPU0_SB_DQ<0>
  VSS44  = GND
  DQ1_B  = M_K_CPU0_SB_DQ<1>
  VSS45  = GND
  DQS0_B_T  = M_K_CPU0_SB_DQS_DP<0>
  DQS0_B_C  = M_K_CPU0_SB_DQS_DN<0>
  VSS46  = GND
  DQ4_B  = M_K_CPU0_SB_DQ<4>
  VSS47  = GND
  DQ5_B  = M_K_CPU0_SB_DQ<5>
  VSS48  = GND
  DQ8_B  = M_K_CPU0_SB_DQ<8>
  VSS49  = GND
  DQ9_B  = M_K_CPU0_SB_DQ<9>
  VSS50  = GND
  DQS1_B_T  = M_K_CPU0_SB_DQS_DP<1>
  DQS1_B_C  = M_K_CPU0_SB_DQS_DN<1>
  VSS51  = GND
  DQ12_B  = M_K_CPU0_SB_DQ<12>
  VSS52  = GND
  DQ13_B  = M_K_CPU0_SB_DQ<13>
  VSS53  = GND
  DQ16_B  = M_K_CPU0_SB_DQ<16>
  VSS54  = GND
  DQ17_B  = M_K_CPU0_SB_DQ<17>
  VSS55  = GND
  DQS2_B_T  = M_K_CPU0_SB_DQS_DP<2>
  DQS2_B_C  = M_K_CPU0_SB_DQS_DN<2>
  VSS56  = GND
  DQ20_B  = M_K_CPU0_SB_DQ<20>
  VSS57  = GND
  DQ21_B  = M_K_CPU0_SB_DQ<21>
  VSS58  = GND
  DQ24_B  = M_K_CPU0_SB_DQ<24>
  VSS59  = GND
  DQ25_B  = M_K_CPU0_SB_DQ<25>
  VSS60  = GND
  DQS3_B_T  = M_K_CPU0_SB_DQS_DP<3>
  DQS3_B_C  = M_K_CPU0_SB_DQS_DN<3>
  VSS61  = GND
  DQ28_B  = M_K_CPU0_SB_DQ<28>
  VSS62  = GND
  DQ29_B  = M_K_CPU0_SB_DQ<29>
  VSS63  = GND
  RFU1  = NC
  VIN_BULK1  = P12V_MEM_CPU0
  VIN_BULK2  = P12V_MEM_CPU0
  \pwr_good||fail_n\  = PWRGD_CHK_CPU0_DIMM
  HAS  = PD_CHK_CPU0_DIMM_SAA
  RFU2  = NC
  RFU3  = NC
  VSS64  = GND
  DQ2_A  = M_K_CPU0_SA_DQ<2>
  VSS65  = GND
  DQ3_A  = M_K_CPU0_SA_DQ<3>
  VSS66  = GND
  \dqs5_a_c||tdqs5_a_c||dqs5_a_t||tdqs5_a_t\  = M_K_CPU0_SA_DQS_DN<5>
  \dqs5_a_t||tdqs5_a_t\  = M_K_CPU0_SA_DQS_DP<5>
  VSS67  = GND
  DQ6_A  = M_K_CPU0_SA_DQ<6>
  VSS68  = GND
  DQ7_A  = M_K_CPU0_SA_DQ<7>
  VSS69  = GND
  DQ10_A  = M_K_CPU0_SA_DQ<10>
  VSS70  = GND
  DQ11_A  = M_K_CPU0_SA_DQ<11>
  VSS71  = GND
  \dqs6_a_c||tdqs6_a_c||dqs6_a_t||tdqs6_a_t\  = M_K_CPU0_SA_DQS_DN<6>
  \dqs6_a_t||tdqs6_a_t\  = M_K_CPU0_SA_DQS_DP<6>
  VSS72  = GND
  DQ14_A  = M_K_CPU0_SA_DQ<14>
  VSS73  = GND
  DQ15_A  = M_K_CPU0_SA_DQ<15>
  VSS74  = GND
  DQ18_A  = M_K_CPU0_SA_DQ<18>
  VSS75  = GND
  DQ19_A  = M_K_CPU0_SA_DQ<19>
  VSS76  = GND
  \dqs7_a_c||tdqs7_a_c\  = M_K_CPU0_SA_DQS_DN<7>
  \dqs7_a_t||tdqs7_a_t\  = M_K_CPU0_SA_DQS_DP<7>
  VSS77  = GND
  DQ22_A  = M_K_CPU0_SA_DQ<22>
  VSS78  = GND
  DQ23_A  = M_K_CPU0_SA_DQ<23>
  VSS79  = GND
  DQ26_A  = M_K_CPU0_SA_DQ<26>
  VSS80  = GND
  DQ27_A  = M_K_CPU0_SA_DQ<27>
  VSS81  = GND
  \dqs8_a_c||tdqs8_a_c\  = M_K_CPU0_SA_DQS_DN<8>
  \dqs8_a_t||tdqs8_a_t\  = M_K_CPU0_SA_DQS_DP<8>
  VSS82  = GND
  DQ30_A  = M_K_CPU0_SA_DQ<30>
  VSS83  = GND
  DQ31_A  = M_K_CPU0_SA_DQ<31>
  VSS84  = GND
  CB2_A  = M_K_CPU0_SA_CB<2>
  VSS85  = GND
  CB3_A  = M_K_CPU0_SA_CB<3>
  VSS86  = GND
  \dqs9_a_c||tdqs9_a_c\  = M_K_CPU0_SA_DQS_DN<9>
  \dqs9_a_t||tdqs9_a_t\  = M_K_CPU0_SA_DQS_DP<9>
  VSS87  = GND
  CB6_A  = M_K_CPU0_SA_CB<6>
  VSS88  = GND
  CB7_A  = M_K_CPU0_SA_CB<7>
  VSS89  = GND
  RESET_N  = M_K_CPU0_RESET_N
  VSS90  = GND
  CS1_A_N  = M_K_CPU0_SA_CS_N<1>
  VSS91  = GND
  CA1_A  = M_K_CPU0_SA_CA<1>
  VSS92  = GND
  CA3_A  = M_K_CPU0_SA_CA<3>
  VSS93  = GND
  CA5_A  = M_K_CPU0_SA_CA<5>
  VSS94  = GND
  CK_T  = M_K_CPU0_CLK_DP<0>
  CK_C  = M_K_CPU0_CLK_DN<0>
  VSS95  = GND
  RFU4  = NC
  CA1_B  = M_K_CPU0_SB_CA<1>
  VSS96  = GND
  CA3_B  = M_K_CPU0_SB_CA<3>
  VSS97  = GND
  CA5_B  = M_K_CPU0_SB_CA<5>
  VSS98  = GND
  PAR_B  = M_K_CPU0_SB_PAR
  VSS99  = GND
  CS1_B_N  = M_K_CPU0_SB_CS_N<1>
  VSS100  = GND
  RFU5  = NC
  RFU6  = NC
  VSS101  = GND
  CB6_B  = M_K_CPU0_SB_CB<6>
  VSS102  = GND
  CB7_B  = M_K_CPU0_SB_CB<7>
  VSS103  = GND
  DQS4_B_C  = M_K_CPU0_SB_DQS_DN<4>
  DQS4_B_T  = M_K_CPU0_SB_DQS_DP<4>
  VSS104  = GND
  CB2_B  = M_K_CPU0_SB_CB<2>
  VSS105  = GND
  CB3_B  = M_K_CPU0_SB_CB<3>
  VSS106  = GND
  DQ2_B  = M_K_CPU0_SB_DQ<2>
  VSS107  = GND
  DQ3_B  = M_K_CPU0_SB_DQ<3>
  VSS108  = GND
  \dqs5_b_c||tdqs5_b_c\  = M_K_CPU0_SB_DQS_DN<5>
  \dqs5_b_t||tdqs5_b_t\  = M_K_CPU0_SB_DQS_DP<5>
  VSS109  = GND
  DQ6_B  = M_K_CPU0_SB_DQ<6>
  VSS110  = GND
  DQ7_B  = M_K_CPU0_SB_DQ<7>
  VSS111  = GND
  DQ10_B  = M_K_CPU0_SB_DQ<10>
  VSS112  = GND
  DQ11_B  = M_K_CPU0_SB_DQ<11>
  VSS113  = GND
  \dqs6_b_c||tdqs6_b_c\  = M_K_CPU0_SB_DQS_DN<6>
  \dqs6_b_t||tdqs6_b_t\  = M_K_CPU0_SB_DQS_DP<6>
  VSS114  = GND
  DQ14_B  = M_K_CPU0_SB_DQ<14>
  VSS115  = GND
  DQ15_B  = M_K_CPU0_SB_DQ<15>
  VSS116  = GND
  DQ18_B  = M_K_CPU0_SB_DQ<18>
  VSS117  = GND
  DQ19_B  = M_K_CPU0_SB_DQ<19>
  VSS118  = GND
  \dqs7_b_c||tdqs7_b_c\  = M_K_CPU0_SB_DQS_DN<7>
  \dqs7_b_t||tdqs7_b_t\  = M_K_CPU0_SB_DQS_DP<7>
  VSS119  = GND
  DQ22_B  = M_K_CPU0_SB_DQ<22>
  VSS120  = GND
  DQ23_B  = M_K_CPU0_SB_DQ<23>
  VSS121  = GND
  DQ26_B  = M_K_CPU0_SB_DQ<26>
  VSS122  = GND
  DQ27_B  = M_K_CPU0_SB_DQ<27>
  VSS123  = GND
  \dqs8_b_c||tdqs8_b_c\  = M_K_CPU0_SB_DQS_DN<8>
  \dqs8_b_t||tdqs8_b_t\  = M_K_CPU0_SB_DQS_DP<8>
  VSS124  = GND
  DQ30_B  = M_K_CPU0_SB_DQ<30>
  VSS125  = GND
  DQ31_B  = M_K_CPU0_SB_DQ<31>
  VSS126  = GND
  G1  = GND
  G2  = GND
  G3  = GND

(kicad_pcb
	(version 20260206)
	(generator "pcbnew")
	(generator_version "10.0")
	(general
		(thickness 1.6)
		(legacy_teardrops no)
	)
	(paper "A4")
	(title_block
		(title "04192023_DAF0TMB3IC0_F0TG_MB_C_brd_V02_OCP.brd")
		(comment 1 "Grand Teton / footprint 2165 of 8354 (J20), pads 185-230 of 291")
	)
	(layers
		(0 "F.Cu" signal "TOP")
		(4 "In1.Cu" signal "GND")
		(6 "In2.Cu" signal "IN1")
		(8 "In3.Cu" signal "GND1")
		(10 "In4.Cu" signal "IN2")
		(12 "In5.Cu" signal "GND2")
		(14 "In6.Cu" signal "IN3")
		(16 "In7.Cu" signal "GND3")
		(18 "In8.Cu" signal "VCC")
		(20 "In9.Cu" signal "VCC1")
		(22 "In10.Cu" signal "GND4")
		(24 "In11.Cu" signal "IN4")
		(26 "In12.Cu" signal "GND5")
		(28 "In13.Cu" signal "IN5")
		(30 "In14.Cu" signal "GND6")
		(32 "In15.Cu" signal "IN6")
		(34 "In16.Cu" signal "GND7")
		(2 "B.Cu" signal "BOTTOM")
		(9 "F.Adhes" user "F.Adhesive")
		(11 "B.Adhes" user "B.Adhesive")
		(13 "F.Paste" user "Package Geometry/Pastemask Top")
		(15 "B.Paste" user "Package Geometry/Pastemask Bottom")
		(5 "F.SilkS" user "Ref Des/Silkscreen Top")
		(7 "B.SilkS" user "Ref Des/Silkscreen Bottom")
		(1 "F.Mask" user "Board Geometry/Soldermask Top")
		(3 "B.Mask" user "Board Geometry/Soldermask Bottom")
		(17 "Dwgs.User" user "User.Drawings")
		(19 "Cmts.User" user "User.Comments")
		(21 "Eco1.User" user "User.Eco1")
		(23 "Eco2.User" user "User.Eco2")
		(25 "Edge.Cuts" user "Board Geometry/Outline")
		(27 "Margin" user)
		(31 "F.CrtYd" user "Package Geometry/Place Bound Top")
		(29 "B.CrtYd" user "Package Geometry/Place Bound Bottom")
		(35 "F.Fab" user "Ref Des/Assembly Top")
		(33 "B.Fab" user "Ref Des/Assembly Bottom")
	)
	(footprint ""
		(layer "F.Cu")
		(at 444.594234 -255.560068 180)
		(property "Reference" "J20"
			(at 1.631188 -81.796128 0)
			(unlocked yes)
			(layer "F.SilkS")
			(effects
				(font
					(size 0.7874 0.5842)
					(thickness 0.1524)
				)
			)
		)
		(property "Value" ""
			(at 0 0 180)
			(layer "F.Fab")
			(effects
				(font
					(size 1.27 1.27)
				)
			)
		)
		(duplicate_pad_numbers_are_jumpers no)
		(pad "185" smd rect
			(at 2.050034 -29.325062 90)
			(size 0.519938 1.4986)
			(layers "F.Cu" "F.Mask" "F.Paste")
			(net "M_K_CPU0_SA_DQ<26>")
		)
		(pad "186" smd rect
			(at 2.050034 -28.474924 90)
			(size 0.519938 1.4986)
			(layers "F.Cu" "F.Mask" "F.Paste")
			(net "GND")
		)
		(pad "187" smd rect
			(at 2.050034 -27.62504 90)
			(size 0.519938 1.4986)
			(layers "F.Cu" "F.Mask" "F.Paste")
			(net "M_K_CPU0_SA_DQ<27>")
		)
		(pad "188" smd rect
			(at 2.050034 -26.774902 90)
			(size 0.519938 1.4986)
			(layers "F.Cu" "F.Mask" "F.Paste")
			(net "GND")
		)
		(pad "189" smd rect
			(at 2.050034 -25.925018 90)
			(size 0.519938 1.4986)
			(layers "F.Cu" "F.Mask" "F.Paste")
			(net "M_K_CPU0_SA_DQS_DN<8>")
		)
		(pad "190" smd rect
			(at 2.050034 -25.07488 90)
			(size 0.519938 1.4986)
			(layers "F.Cu" "F.Mask" "F.Paste")
			(net "M_K_CPU0_SA_DQS_DP<8>")
		)
		(pad "191" smd rect
			(at 2.050034 -24.224996 90)
			(size 0.519938 1.4986)
			(layers "F.Cu" "F.Mask" "F.Paste")
			(net "GND")
		)
		(pad "192" smd rect
			(at 2.050034 -23.375112 90)
			(size 0.519938 1.4986)
			(layers "F.Cu" "F.Mask" "F.Paste")
			(net "M_K_CPU0_SA_DQ<30>")
		)
		(pad "193" smd rect
			(at 2.050034 -22.524974 90)
			(size 0.519938 1.4986)
			(layers "F.Cu" "F.Mask" "F.Paste")
			(net "GND")
		)
		(pad "194" smd rect
			(at 2.050034 -21.67509 90)
			(size 0.519938 1.4986)
			(layers "F.Cu" "F.Mask" "F.Paste")
			(net "M_K_CPU0_SA_DQ<31>")
		)
		(pad "195" smd rect
			(at 2.050034 -20.824952 90)
			(size 0.519938 1.4986)
			(layers "F.Cu" "F.Mask" "F.Paste")
			(net "GND")
		)
		(pad "196" smd rect
			(at 2.050034 -19.975068 90)
			(size 0.519938 1.4986)
			(layers "F.Cu" "F.Mask" "F.Paste")
			(net "M_K_CPU0_SA_CB<2>")
		)
		(pad "197" smd rect
			(at 2.050034 -19.12493 90)
			(size 0.519938 1.4986)
			(layers "F.Cu" "F.Mask" "F.Paste")
			(net "GND")
		)
		(pad "198" smd rect
			(at 2.050034 -18.275046 90)
			(size 0.519938 1.4986)
			(layers "F.Cu" "F.Mask" "F.Paste")
			(net "M_K_CPU0_SA_CB<3>")
		)
		(pad "199" smd rect
			(at 2.050034 -17.424908 90)
			(size 0.519938 1.4986)
			(layers "F.Cu" "F.Mask" "F.Paste")
			(net "GND")
		)
		(pad "200" smd rect
			(at 2.050034 -16.575024 90)
			(size 0.519938 1.4986)
			(layers "F.Cu" "F.Mask" "F.Paste")
			(net "M_K_CPU0_SA_DQS_DN<9>")
		)
		(pad "201" smd rect
			(at 2.050034 -15.724886 90)
			(size 0.519938 1.4986)
			(layers "F.Cu" "F.Mask" "F.Paste")
			(net "M_K_CPU0_SA_DQS_DP<9>")
		)
		(pad "202" smd rect
			(at 2.050034 -14.875002 90)
			(size 0.519938 1.4986)
			(layers "F.Cu" "F.Mask" "F.Paste")
			(net "GND")
		)
		(pad "203" smd rect
			(at 2.050034 -14.025118 90)
			(size 0.519938 1.4986)
			(layers "F.Cu" "F.Mask" "F.Paste")
			(net "M_K_CPU0_SA_CB<6>")
		)
		(pad "204" smd rect
			(at 2.050034 -13.17498 90)
			(size 0.519938 1.4986)
			(layers "F.Cu" "F.Mask" "F.Paste")
			(net "GND")
		)
		(pad "205" smd rect
			(at 2.050034 -12.325096 90)
			(size 0.519938 1.4986)
			(layers "F.Cu" "F.Mask" "F.Paste")
			(net "M_K_CPU0_SA_CB<7>")
		)
		(pad "206" smd rect
			(at 2.050034 -11.474958 90)
			(size 0.519938 1.4986)
			(layers "F.Cu" "F.Mask" "F.Paste")
			(net "GND")
		)
		(pad "207" smd rect
			(at 2.050034 -10.625074 90)
			(size 0.519938 1.4986)
			(layers "F.Cu" "F.Mask" "F.Paste")
			(net "M_K_CPU0_RESET_N")
		)
		(pad "208" smd rect
			(at 2.050034 -9.774936 90)
			(size 0.519938 1.4986)
			(layers "F.Cu" "F.Mask" "F.Paste")
			(net "GND")
		)
		(pad "209" smd rect
			(at 2.050034 -8.925052 90)
			(size 0.519938 1.4986)
			(layers "F.Cu" "F.Mask" "F.Paste")
			(net "M_K_CPU0_SA_CS_N<1>")
		)
		(pad "210" smd rect
			(at 2.050034 -8.074914 90)
			(size 0.519938 1.4986)
			(layers "F.Cu" "F.Mask" "F.Paste")
			(net "GND")
		)
		(pad "211" smd rect
			(at 2.050034 -7.22503 90)
			(size 0.519938 1.4986)
			(layers "F.Cu" "F.Mask" "F.Paste")
			(net "M_K_CPU0_SA_CA<1>")
		)
		(pad "212" smd rect
			(at 2.050034 -6.374892 90)
			(size 0.519938 1.4986)
			(layers "F.Cu" "F.Mask" "F.Paste")
			(net "GND")
		)
		(pad "213" smd rect
			(at 2.050034 -5.525008 90)
			(size 0.519938 1.4986)
			(layers "F.Cu" "F.Mask" "F.Paste")
			(net "M_K_CPU0_SA_CA<3>")
		)
		(pad "214" smd rect
			(at 2.050034 -4.675124 90)
			(size 0.519938 1.4986)
			(layers "F.Cu" "F.Mask" "F.Paste")
			(net "GND")
		)
		(pad "215" smd rect
			(at 2.050034 -3.824986 90)
			(size 0.519938 1.4986)
			(layers "F.Cu" "F.Mask" "F.Paste")
			(net "M_K_CPU0_SA_CA<5>")
		)
		(pad "216" smd rect
			(at 2.050034 -2.975102 90)
			(size 0.519938 1.4986)
			(layers "F.Cu" "F.Mask" "F.Paste")
			(net "GND")
		)
		(pad "217" smd rect
			(at 2.050034 -2.124964 90)
			(size 0.519938 1.4986)
			(layers "F.Cu" "F.Mask" "F.Paste")
			(net "M_K_CPU0_CLK_DP<0>")
		)
		(pad "218" smd rect
			(at 2.050034 -1.27508 90)
			(size 0.519938 1.4986)
			(layers "F.Cu" "F.Mask" "F.Paste")
			(net "M_K_CPU0_CLK_DN<0>")
		)
		(pad "219" smd rect
			(at 2.050034 -0.424942 90)
			(size 0.519938 1.4986)
			(layers "F.Cu" "F.Mask" "F.Paste")
			(net "GND")
		)
		(pad "220" smd rect
			(at 2.050034 5.525008 90)
			(size 0.519938 1.4986)
			(layers "F.Cu" "F.Mask" "F.Paste")
			(net "Net_2393")
		)
		(pad "221" smd rect
			(at 2.050034 6.374892 90)
			(size 0.519938 1.4986)
			(layers "F.Cu" "F.Mask" "F.Paste")
			(net "M_K_CPU0_SB_CA<1>")
		)
		(pad "222" smd rect
			(at 2.050034 7.22503 90)
			(size 0.519938 1.4986)
			(layers "F.Cu" "F.Mask" "F.Paste")
			(net "GND")
		)
		(pad "223" smd rect
			(at 2.050034 8.074914 90)
			(size 0.519938 1.4986)
			(layers "F.Cu" "F.Mask" "F.Paste")
			(net "M_K_CPU0_SB_CA<3>")
		)
		(pad "224" smd rect
			(at 2.050034 8.925052 90)
			(size 0.519938 1.4986)
			(layers "F.Cu" "F.Mask" "F.Paste")
			(net "GND")
		)
		(pad "225" smd rect
			(at 2.050034 9.774936 90)
			(size 0.519938 1.4986)
			(layers "F.Cu" "F.Mask" "F.Paste")
			(net "M_K_CPU0_SB_CA<5>")
		)
		(pad "226" smd rect
			(at 2.050034 10.625074 90)
			(size 0.519938 1.4986)
			(layers "F.Cu" "F.Mask" "F.Paste")
			(net "GND")
		)
		(pad "227" smd rect
			(at 2.050034 11.474958 90)
			(size 0.519938 1.4986)
			(layers "F.Cu" "F.Mask" "F.Paste")
			(net "M_K_CPU0_SB_PAR")
		)
		(pad "228" smd rect
			(at 2.050034 12.325096 90)
			(size 0.519938 1.4986)
			(layers "F.Cu" "F.Mask" "F.Paste")
			(net "GND")
		)
		(pad "229" smd rect
			(at 2.050034 13.17498 90)
			(size 0.519938 1.4986)
			(layers "F.Cu" "F.Mask" "F.Paste")
			(net "M_K_CPU0_SB_CS_N<1>")
		)
		(pad "230" smd rect
			(at 2.050034 14.025118 90)
			(size 0.519938 1.4986)
			(layers "F.Cu" "F.Mask" "F.Paste")
			(net "GND")
		)
	)
)
